(kicad_pcb
	(version 20260206)
	(generator "pcbnew")
	(generator_version "10.0")
	(general
		(thickness 1.6)
		(legacy_teardrops no)
	)
	(paper "A4")
	(title_block
		(title "01162023_DA0F0TEBIF0_F0T_Expander_BD_F_brd_V02_OCP.brd")
		(comment 1 "Grand Teton / footprints 951-954 of 9728")
	)
	(layers
		(0 "F.Cu" signal "TOP")
		(4 "In1.Cu" signal "GND")
		(6 "In2.Cu" signal "VCC")
		(8 "In3.Cu" signal "VCC1")
		(10 "In4.Cu" signal "GND1")
		(12 "In5.Cu" signal "IN1")
		(14 "In6.Cu" signal "GND2")
		(16 "In7.Cu" signal "IN2")
		(18 "In8.Cu" signal "GND3")
		(20 "In9.Cu" signal "IN3")
		(22 "In10.Cu" signal "GND4")
		(24 "In11.Cu" signal "IN4")
		(26 "In12.Cu" signal "GND5")
		(28 "In13.Cu" signal "IN5")
		(30 "In14.Cu" signal "GND6")
		(32 "In15.Cu" signal "IN6")
		(34 "In16.Cu" signal "GND7")
		(2 "B.Cu" signal "BOTTOM")
		(9 "F.Adhes" user "F.Adhesive")
		(11 "B.Adhes" user "B.Adhesive")
		(13 "F.Paste" user "Package Geometry/Pastemask Top")
		(15 "B.Paste" user "Package Geometry/Pastemask Bottom")
		(5 "F.SilkS" user "Ref Des/Silkscreen Top")
		(7 "B.SilkS" user "Ref Des/Silkscreen Bottom")
		(1 "F.Mask" user "Board Geometry/Soldermask Top")
		(3 "B.Mask" user "Board Geometry/Soldermask Bottom")
		(17 "Dwgs.User" user "User.Drawings")
		(19 "Cmts.User" user "User.Comments")
		(21 "Eco1.User" user "User.Eco1")
		(23 "Eco2.User" user "User.Eco2")
		(25 "Edge.Cuts" user "Board Geometry/Outline")
		(27 "Margin" user)
		(31 "F.CrtYd" user "Package Geometry/Place Bound Top")
		(29 "B.CrtYd" user "Package Geometry/Place Bound Bottom")
		(35 "F.Fab" user "Ref Des/Assembly Top")
		(33 "B.Fab" user "Ref Des/Assembly Bottom")
	)
	(footprint ""
		(layer "F.Cu")
		(at 455.912982 -111.785654 180)
		(property "Reference" "PU106"
			(at 4.045712 -2.362454 90)
			(unlocked yes)
			(layer "F.SilkS")
			(effects
				(font
					(size 0.7874 0.5842)
					(thickness 0.1524)
				)
				(justify left)
			)
		)
		(property "Value" ""
			(at 0 0 180)
			(layer "F.Fab")
			(effects
				(font
					(size 1.27 1.27)
				)
			)
		)
		(duplicate_pad_numbers_are_jumpers no)
		(fp_line
			(start 1.549908 2.549906)
			(end 1.549908 2.253996)
			(stroke
				(width 0.1524)
				(type default)
			)
			(layer "F.SilkS")
		)
		(fp_line
			(start 1.549908 -2.253996)
			(end 1.549908 -2.549906)
			(stroke
				(width 0.1524)
				(type default)
			)
			(layer "F.SilkS")
		)
		(fp_line
			(start 1.549908 -2.549906)
			(end 0.752094 -2.549906)
			(stroke
				(width 0.1524)
				(type default)
			)
			(layer "F.SilkS")
		)
		(fp_line
			(start 0.753872 2.549906)
			(end 1.549908 2.549906)
			(stroke
				(width 0.1524)
				(type default)
			)
			(layer "F.SilkS")
		)
		(fp_line
			(start 0.2413 -2.549906)
			(end -0.2413 -2.549906)
			(stroke
				(width 0.1524)
				(type default)
			)
			(layer "F.SilkS")
		)
		(fp_line
			(start -0.245872 2.549906)
			(end 0.245872 2.549906)
			(stroke
				(width 0.1524)
				(type default)
			)
			(layer "F.SilkS")
		)
		(fp_line
			(start -0.752094 -2.549906)
			(end -1.549908 -2.549906)
			(stroke
				(width 0.1524)
				(type default)
			)
			(layer "F.SilkS")
		)
		(fp_line
			(start -1.549908 2.549906)
			(end -0.753872 2.549906)
			(stroke
				(width 0.1524)
				(type default)
			)
			(layer "F.SilkS")
		)
		(fp_line
			(start -1.549908 2.253996)
			(end -1.549908 2.549906)
			(stroke
				(width 0.1524)
				(type default)
			)
			(layer "F.SilkS")
		)
		(fp_line
			(start -1.549908 -2.549906)
			(end -1.549908 -2.251964)
			(stroke
				(width 0.1524)
				(type default)
			)
			(layer "F.SilkS")
		)
		(fp_poly
			(pts
				(xy -2.367026 -1.999996) (xy -3.218688 -1.574292) (xy -3.218688 -2.4257)
			)
			(stroke
				(width 0)
				(type default)
			)
			(fill yes)
			(layer "F.SilkS")
		)
		(fp_line
			(start 1.549908 2.549906)
			(end 1.549908 -2.549906)
			(stroke
				(width 0.1)
				(type default)
			)
			(layer "F.Fab")
		)
		(fp_line
			(start 1.549908 -2.549906)
			(end -1.549908 -2.549906)
			(stroke
				(width 0.1)
				(type default)
			)
			(layer "F.Fab")
		)
		(fp_line
			(start -1.549908 2.549906)
			(end 1.549908 2.549906)
			(stroke
				(width 0.1)
				(type default)
			)
			(layer "F.Fab")
		)
		(fp_line
			(start -1.549908 -2.549906)
			(end -1.549908 2.549906)
			(stroke
				(width 0.1)
				(type default)
			)
			(layer "F.Fab")
		)
		(fp_poly
			(pts
				(xy -1.891538 -1.999996) (xy -2.7432 -1.574292) (xy -2.7432 -2.4257)
			)
			(stroke
				(width 0)
				(type default)
			)
			(fill yes)
			(layer "F.Fab")
		)
		(fp_text user "12"
			(at 2.552954 0.973836 90)
			(unlocked yes)
			(layer "F.SilkS")
			(effects
				(font
					(size 0.635 0.4064)
					(thickness 0.1524)
				)
			)
		)
		(fp_text user "20"
			(at 2.055368 -2.7686 90)
			(unlocked yes)
			(layer "F.SilkS")
			(effects
				(font
					(size 0.635 0.4064)
					(thickness 0.1524)
				)
			)
		)
		(fp_text user "11"
			(at 1.22936 2.978912 0)
			(unlocked yes)
			(layer "F.SilkS")
			(effects
				(font
					(size 0.635 0.4064)
					(thickness 0.1524)
				)
			)
		)
		(fp_text user "10"
			(at -1.325626 3.103118 0)
			(unlocked yes)
			(layer "F.SilkS")
			(effects
				(font
					(size 0.635 0.4064)
					(thickness 0.1524)
				)
			)
		)
		(fp_text user "21_22"
			(at -1.44653 -3.602228 0)
			(unlocked yes)
			(layer "F.SilkS")
			(effects
				(font
					(size 0.635 0.4064)
					(thickness 0.1524)
				)
			)
		)
		(fp_text user "9"
			(at -2.181098 2.411476 0)
			(unlocked yes)
			(layer "F.SilkS")
			(effects
				(font
					(size 0.635 0.4064)
					(thickness 0.1524)
				)
			)
		)
		(fp_text user "12"
			(at 2.207768 2.7178 90)
			(unlocked yes)
			(layer "F.Fab")
			(effects
				(font
					(size 0.635 0.4064)
					(thickness 0.1524)
				)
			)
		)
		(fp_text user "20"
			(at 2.055368 -2.7686 90)
			(unlocked yes)
			(layer "F.Fab")
			(effects
				(font
					(size 0.635 0.4064)
					(thickness 0.1524)
				)
			)
		)
		(fp_text user "11"
			(at 1.1938 3.329432 180)
			(unlocked yes)
			(layer "F.Fab")
			(effects
				(font
					(size 0.635 0.4064)
					(thickness 0.1524)
				)
			)
		)
		(fp_text user "21_22"
			(at -0.0762 -3.401568 180)
			(unlocked yes)
			(layer "F.Fab")
			(effects
				(font
					(size 0.635 0.4064)
					(thickness 0.1524)
				)
			)
		)
		(fp_text user "10"
			(at -1.4224 3.253232 180)
			(unlocked yes)
			(layer "F.Fab")
			(effects
				(font
					(size 0.635 0.4064)
					(thickness 0.1524)
				)
			)
		)
		(fp_text user "9"
			(at -2.338832 2.5908 90)
			(unlocked yes)
			(layer "F.Fab")
			(effects
				(font
					(size 0.635 0.4064)
					(thickness 0.1524)
				)
			)
		)
		(pad "1" smd circle
			(at -1.374902 -1.999996 90)
			(size 0 0)
			(layers "F.Cu" "F.Mask" "F.Paste")
			(net "P12V_NIC7_CO_EN")
		)
		(pad "2" smd rect
			(at -1.400048 -1.500124 90)
			(size 0.254 0.8128)
			(layers "F.Cu" "F.Mask" "F.Paste")
			(net "GND")
		)
		(pad "3" smd rect
			(at -1.400048 -0.999998 90)
			(size 0.254 0.8128)
			(layers "F.Cu" "F.Mask" "F.Paste")
			(net "GND")
		)
		(pad "4" smd rect
			(at -1.400048 -0.499872 90)
			(size 0.254 0.8128)
			(layers "F.Cu" "F.Mask" "F.Paste")
			(net "P12V_NIC7_CO_TIMER")
		)
		(pad "5" smd rect
			(at -1.400048 0 90)
			(size 0.254 0.8128)
			(layers "F.Cu" "F.Mask" "F.Paste")
			(net "P12V_NIC7_CO_ISET")
		)
		(pad "6" smd rect
			(at -1.400048 0.499872 90)
			(size 0.254 0.8128)
			(layers "F.Cu" "F.Mask" "F.Paste")
			(net "P12V_NIC7_CO_SS")
		)
		(pad "7" smd rect
			(at -1.400048 0.999998 90)
			(size 0.254 0.8128)
			(layers "F.Cu" "F.Mask" "F.Paste")
			(net "GND")
		)
		(pad "8" smd rect
			(at -1.400048 1.500124 90)
			(size 0.254 0.8128)
			(layers "F.Cu" "F.Mask" "F.Paste")
			(net "P12V_NIC7_CO_IMON_VR")
		)
		(pad "9" smd rect
			(at -1.400048 1.999996 90)
			(size 0.254 0.8128)
			(layers "F.Cu" "F.Mask" "F.Paste")
			(net "P12V_NIC7_CO_FLTB")
		)
		(pad "10" smd rect
			(at -0.499872 2.400046 180)
			(size 0.254 0.8128)
			(layers "F.Cu" "F.Mask" "F.Paste")
			(net "PWRGD_P12V_NIC7_CO")
		)
		(pad "11" smd rect
			(at 0.499872 2.400046 180)
			(size 0.254 0.8128)
			(layers "F.Cu" "F.Mask" "F.Paste")
			(net "P12V_NIC7_CO_OV_FB")
		)
		(pad "12" smd rect
			(at 1.400048 1.999996 90)
			(size 0.254 0.8128)
			(layers "F.Cu" "F.Mask" "F.Paste")
			(net "P12V_NIC7_CO_AVIN_PD")
		)
		(pad "13" smd rect
			(at 1.400048 1.500124 90)
			(size 0.254 0.8128)
			(layers "F.Cu" "F.Mask" "F.Paste")
			(net "P12V_NIC7_R")
		)
		(pad "14" smd rect
			(at 1.400048 0.999998 90)
			(size 0.254 0.8128)
			(layers "F.Cu" "F.Mask" "F.Paste")
			(net "P12V_NIC7_R")
		)
		(pad "15" smd rect
			(at 1.400048 0.499872 90)
			(size 0.254 0.8128)
			(layers "F.Cu" "F.Mask" "F.Paste")
			(net "P12V_NIC7_R")
		)
		(pad "16" smd rect
			(at 1.400048 0 90)
			(size 0.254 0.8128)
			(layers "F.Cu" "F.Mask" "F.Paste")
			(net "P12V_NIC7_R")
		)
		(pad "17" smd rect
			(at 1.400048 -0.499872 90)
			(size 0.254 0.8128)
			(layers "F.Cu" "F.Mask" "F.Paste")
			(net "P12V_NIC7_R")
		)
		(pad "18" smd rect
			(at 1.400048 -0.999998 90)
			(size 0.254 0.8128)
			(layers "F.Cu" "F.Mask" "F.Paste")
			(net "P12V_NIC7_R")
		)
		(pad "19" smd rect
			(at 1.400048 -1.500124 90)
			(size 0.254 0.8128)
			(layers "F.Cu" "F.Mask" "F.Paste")
			(net "P12V_NIC7_R")
		)
		(pad "20" smd rect
			(at 1.400048 -1.999996 90)
			(size 0.254 0.8128)
			(layers "F.Cu" "F.Mask" "F.Paste")
			(net "P12V_NIC7_R")
		)
		(pad "21_22" smd circle
			(at 0.499872 -2.337562 90)
			(size 0 0)
			(layers "F.Cu" "F.Mask" "F.Paste")
			(net "P12V_AUX")
		)
		(pad "23" smd rect
			(at 0 -1.100074 90)
			(size 0.254 1.27)
			(layers "F.Cu" "F.Mask" "F.Paste")
			(net "P12V_AUX")
		)
		(pad "24" smd rect
			(at 0 -0.199898 90)
			(size 0.254 1.27)
			(layers "F.Cu" "F.Mask" "F.Paste")
			(net "P12V_AUX")
		)
		(pad "25" smd rect
			(at 0 0.700024 90)
			(size 0.254 1.27)
			(layers "F.Cu" "F.Mask" "F.Paste")
			(net "P12V_AUX")
		)
		(pad "26" smd rect
			(at 0 1.599946 90)
			(size 0.254 1.27)
			(layers "F.Cu" "F.Mask" "F.Paste")
			(net "P12V_AUX")
		)
	)
	(footprint ""
		(layer "F.Cu")
		(at 146.253454 -281.789632)
		(property "Reference" "L112"
			(at 0 0 0)
			(layer "F.SilkS")
			(hide yes)
			(effects
				(font
					(size 1.27 1.27)
				)
			)
		)
		(property "Value" ""
			(at 0 0 0)
			(layer "F.Fab")
			(effects
				(font
					(size 1.27 1.27)
				)
			)
		)
		(duplicate_pad_numbers_are_jumpers no)
		(fp_line
			(start -1.63576 -0.8128)
			(end -1.63576 0.8128)
			(stroke
				(width 0.1524)
				(type default)
			)
			(layer "F.SilkS")
		)
		(fp_line
			(start -1.63576 -0.8128)
			(end 1.63576 -0.8128)
			(stroke
				(width 0.1524)
				(type default)
			)
			(layer "F.SilkS")
		)
		(fp_line
			(start 1.63576 -0.8128)
			(end 1.63576 0.8128)
			(stroke
				(width 0.1524)
				(type default)
			)
			(layer "F.SilkS")
		)
		(fp_line
			(start 1.63576 0.8128)
			(end -1.63576 0.8128)
			(stroke
				(width 0.1524)
				(type default)
			)
			(layer "F.SilkS")
		)
		(fp_line
			(start -1.56083 -0.738632)
			(end -1.56083 0.7366)
			(stroke
				(width 0.1)
				(type default)
			)
			(layer "F.Fab")
		)
		(fp_line
			(start -1.56083 0.7366)
			(end -1.524 0.7366)
			(stroke
				(width 0.1)
				(type default)
			)
			(layer "F.Fab")
		)
		(fp_line
			(start -1.524 0.7366)
			(end 1.524 0.7366)
			(stroke
				(width 0.1)
				(type default)
			)
			(layer "F.Fab")
		)
		(fp_line
			(start 1.524 0.7366)
			(end 1.560576 0.7366)
			(stroke
				(width 0.1)
				(type default)
			)
			(layer "F.Fab")
		)
		(fp_line
			(start 1.560576 -0.738632)
			(end -1.56083 -0.738632)
			(stroke
				(width 0.1)
				(type default)
			)
			(layer "F.Fab")
		)
		(fp_line
			(start 1.560576 0.7366)
			(end 1.560576 -0.738632)
			(stroke
				(width 0.1)
				(type default)
			)
			(layer "F.Fab")
		)
		(pad "1" smd rect
			(at -0.94996 0 180)
			(size 1.1176 1.3716)
			(layers "F.Cu" "F.Mask" "F.Paste")
			(net "P1V8_PLL0_PEX1")
		)
		(pad "2" smd rect
			(at 0.94996 0 180)
			(size 1.1176 1.3716)
			(layers "F.Cu" "F.Mask" "F.Paste")
			(net "SYSPLL_VDDA18_PEX1")
		)
	)
	(footprint ""
		(layer "F.Cu")
		(at 433.190904 -55.663846 90)
		(property "Reference" "PU68"
			(at -1.304036 2.97561 90)
			(unlocked yes)
			(layer "F.SilkS")
			(effects
				(font
					(size 0.7874 0.5842)
					(thickness 0.1524)
				)
				(justify left)
			)
		)
		(property "Value" ""
			(at 0 0 90)
			(layer "F.Fab")
			(effects
				(font
					(size 1.27 1.27)
				)
			)
		)
		(duplicate_pad_numbers_are_jumpers no)
		(fp_line
			(start 1.943608 -1.549908)
			(end 1.943608 1.549908)
			(stroke
				(width 0.1524)
				(type default)
			)
			(layer "F.SilkS")
		)
		(fp_line
			(start -1.943608 -1.549908)
			(end 1.943608 -1.549908)
			(stroke
				(width 0.1524)
				(type default)
			)
			(layer "F.SilkS")
		)
		(fp_line
			(start 1.943608 1.549908)
			(end -1.943608 1.549908)
			(stroke
				(width 0.1524)
				(type default)
			)
			(layer "F.SilkS")
		)
		(fp_line
			(start -1.943608 1.549908)
			(end -1.943608 -1.549908)
			(stroke
				(width 0.1524)
				(type default)
			)
			(layer "F.SilkS")
		)
		(fp_poly
			(pts
				(xy -2.019808 -1.549908) (xy -1.257808 -1.549908) (xy -1.257808 -1.880108) (xy -2.019808 -1.880108)
			)
			(stroke
				(width 0)
				(type default)
			)
			(fill yes)
			(layer "F.SilkS")
		)
		(fp_line
			(start 1.549908 -1.549908)
			(end 1.549908 1.549908)
			(stroke
				(width 0.1)
				(type default)
			)
			(layer "F.Fab")
		)
		(fp_line
			(start -1.549908 -1.549908)
			(end 1.549908 -1.549908)
			(stroke
				(width 0.1)
				(type default)
			)
			(layer "F.Fab")
		)
		(fp_line
			(start 1.549908 1.549908)
			(end -1.549908 1.549908)
			(stroke
				(width 0.1)
				(type default)
			)
			(layer "F.Fab")
		)
		(fp_line
			(start -1.549908 1.549908)
			(end -1.549908 -1.549908)
			(stroke
				(width 0.1)
				(type default)
			)
			(layer "F.Fab")
		)
		(fp_poly
			(pts
				(xy -2.019808 -1.549908) (xy -1.257808 -1.549908) (xy -1.257808 -1.880108) (xy -2.019808 -1.880108)
			)
			(stroke
				(width 0)
				(type default)
			)
			(fill yes)
			(layer "F.Fab")
		)
		(pad "1" smd rect
			(at -1.500124 -1.249934)
			(size 0.2794 0.6096)
			(layers "F.Cu" "F.Mask" "F.Paste")
			(net "P3V3_SSD15")
		)
		(pad "2" smd rect
			(at -1.500124 -0.750062)
			(size 0.2794 0.6096)
			(layers "F.Cu" "F.Mask" "F.Paste")
			(net "P3V3_SSD15")
		)
		(pad "3" smd rect
			(at -1.500124 -0.249936)
			(size 0.2794 0.6096)
			(layers "F.Cu" "F.Mask" "F.Paste")
			(net "P3V3_SSD15")
		)
		(pad "4" smd rect
			(at -1.500124 0.249936)
			(size 0.2794 0.6096)
			(layers "F.Cu" "F.Mask" "F.Paste")
			(net "P3V3_SSD15")
		)
		(pad "5" smd rect
			(at -1.500124 0.750062)
			(size 0.2794 0.6096)
			(layers "F.Cu" "F.Mask" "F.Paste")
			(net "P3V3_SSD15")
		)
		(pad "6" smd rect
			(at -1.500124 1.249934)
			(size 0.2794 0.6096)
			(layers "F.Cu" "F.Mask" "F.Paste")
			(net "GND")
		)
		(pad "7" smd rect
			(at 1.500124 1.249934)
			(size 0.2794 0.6096)
			(layers "F.Cu" "F.Mask" "F.Paste")
			(net "P3V3_SSD15_SS")
		)
		(pad "8" smd rect
			(at 1.500124 0.750062)
			(size 0.2794 0.6096)
			(layers "F.Cu" "F.Mask" "F.Paste")
			(net "PWRGD_P3V3_SSD15")
		)
		(pad "9" smd rect
			(at 1.500124 0.249936)
			(size 0.2794 0.6096)
			(layers "F.Cu" "F.Mask" "F.Paste")
			(net "P3V3_SSD15_OCP")
		)
		(pad "10" smd rect
			(at 1.500124 -0.249936)
			(size 0.2794 0.6096)
			(layers "F.Cu" "F.Mask" "F.Paste")
			(net "P5V_AUX")
		)
		(pad "11" smd rect
			(at 1.500124 -0.750062)
			(size 0.2794 0.6096)
			(layers "F.Cu" "F.Mask" "F.Paste")
			(net "SSD15_AUX_P3V3_EN_R")
		)
		(pad "12" smd rect
			(at 1.500124 -1.249934)
			(size 0.2794 0.6096)
			(layers "F.Cu" "F.Mask" "F.Paste")
			(net "P3V3_AUX")
		)
		(pad "13" smd rect
			(at 0 0 90)
			(size 1.9812 2.7178)
			(layers "F.Cu" "F.Mask" "F.Paste")
			(net "P3V3_AUX")
		)
		(zone
			(layer "F.Cu")
			(hatch none 0.5)
			(connect_pads
				(clearance 0)
			)
			(min_thickness 0.25)
			(keepout
				(tracks not_allowed)
				(vias allowed)
				(pads allowed)
				(copperpour not_allowed)
				(footprints allowed)
			)
			(placement
				(enabled no)
				(sheetname "")
			)
			(fill
				(thermal_gap 0.5)
				(thermal_bridge_width 0.5)
				(island_removal_mode 0)
			)
			(polygon
				(pts
					(xy 431.641504 -56.806846) (xy 431.768504 -56.806846) (xy 434.740304 -56.806846) (xy 434.740812 -56.806846)
					(xy 434.740812 -54.520846) (xy 434.740304 -54.520846) (xy 434.613304 -54.520846) (xy 433.190904 -54.520846)
					(xy 433.190904 -54.622446) (xy 434.613304 -54.622446) (xy 434.613304 -56.705246) (xy 431.768504 -56.705246)
					(xy 431.768504 -54.622446) (xy 433.165504 -54.622446) (xy 433.165504 -54.520846) (xy 431.768504 -54.520846)
					(xy 431.641504 -54.520846) (xy 431.640996 -54.520846) (xy 431.640996 -56.806846)
				)
			)
		)
	)
	(footprint ""
		(layer "F.Cu")
		(at 120.626886 -53.697124 -90)
		(property "Reference" "PC508"
			(at 0 0 270)
			(layer "F.SilkS")
			(hide yes)
			(effects
				(font
					(size 1.27 1.27)
				)
			)
		)
		(property "Value" ""
			(at 0 0 270)
			(layer "F.Fab")
			(effects
				(font
					(size 1.27 1.27)
				)
			)
		)
		(duplicate_pad_numbers_are_jumpers no)
		(fp_line
			(start -0.7874 0.4064)
			(end -0.7874 -0.4064)
			(stroke
				(width 0.1524)
				(type default)
			)
			(layer "F.SilkS")
		)
		(fp_line
			(start 0.7874 0.4064)
			(end -0.7874 0.4064)
			(stroke
				(width 0.1524)
				(type default)
			)
			(layer "F.SilkS")
		)
		(fp_line
			(start -0.7874 -0.4064)
			(end 0.7874 -0.4064)
			(stroke
				(width 0.1524)
				(type default)
			)
			(layer "F.SilkS")
		)
		(fp_line
			(start 0.7874 -0.4064)
			(end 0.7874 0.4064)
			(stroke
				(width 0.1524)
				(type default)
			)
			(layer "F.SilkS")
		)
		(fp_line
			(start -0.67945 0.3048)
			(end -0.67945 -0.305054)
			(stroke
				(width 0.1)
				(type default)
			)
			(layer "F.Fab")
		)
		(fp_line
			(start -0.12065 0.3048)
			(end -0.67945 0.3048)
			(stroke
				(width 0.1)
				(type default)
			)
			(layer "F.Fab")
		)
		(fp_line
			(start 0.120396 0.3048)
			(end 0.120396 0.2794)
			(stroke
				(width 0.1)
				(type default)
			)
			(layer "F.Fab")
		)
		(fp_line
			(start 0.67945 0.3048)
			(end 0.120396 0.3048)
			(stroke
				(width 0.1)
				(type default)
			)
			(layer "F.Fab")
		)
		(fp_line
			(start -0.12065 0.2794)
			(end -0.12065 0.3048)
			(stroke
				(width 0.1)
				(type default)
			)
			(layer "F.Fab")
		)
		(fp_line
			(start 0.120396 0.2794)
			(end -0.12065 0.2794)
			(stroke
				(width 0.1)
				(type default)
			)
			(layer "F.Fab")
		)
		(fp_line
			(start -0.12065 -0.2794)
			(end 0.12065 -0.2794)
			(stroke
				(width 0.1)
				(type default)
			)
			(layer "F.Fab")
		)
		(fp_line
			(start 0.12065 -0.2794)
			(end 0.12065 -0.3048)
			(stroke
				(width 0.1)
				(type default)
			)
			(layer "F.Fab")
		)
		(fp_line
			(start 0.12065 -0.3048)
			(end 0.67945 -0.3048)
			(stroke
				(width 0.1)
				(type default)
			)
			(layer "F.Fab")
		)
		(fp_line
			(start 0.67945 -0.3048)
			(end 0.67945 0.3048)
			(stroke
				(width 0.1)
				(type default)
			)
			(layer "F.Fab")
		)
		(fp_line
			(start -0.67945 -0.305054)
			(end -0.12065 -0.305054)
			(stroke
				(width 0.1)
				(type default)
			)
			(layer "F.Fab")
		)
		(fp_line
			(start -0.12065 -0.305054)
			(end -0.12065 -0.2794)
			(stroke
				(width 0.1)
				(type default)
			)
			(layer "F.Fab")
		)
		(pad "1" smd circle
			(at -0.40005 0 270)
			(size 0 0)
			(layers "F.Cu" "F.Mask" "F.Paste")
			(net "P3V3_AUX")
		)
		(pad "2" smd circle
			(at 0.40005 0 270)
			(size 0 0)
			(layers "F.Cu" "F.Mask" "F.Paste")
			(net "GND")
		)
	)
)
